# BASEBOARD_FAB2 (Tioga Pass) — schematic netlist excerpt (pin names and nets, part order shuffled) for the footprints in the layout excerpt that follows; sources: Cadence DE-HDL packaged netlist, KiCad conversion of Wiwynn_Tioga_Pass_MB.brd

C1B3  CAP_A  1.0UF 6.3V 10% X6S  pkg 0402V  page 226 : A = VR_PVDDQ_KLM_VD12 ; B = GND
C5D36  CAP_A  22.0UF 4V 20% X6S  pkg 0603V  page 42 : A = PVCCMCP_CPU0 ; B = GND
C4E22  CAP  1.0UF 16V 10% X6S  pkg 0402  page 214 : A = VR_PVCCIO_CPU1_PH1_VCIN ; B = GND

(kicad_pcb
	(version 20260206)
	(generator "pcbnew")
	(generator_version "10.0")
	(general
		(thickness 1.6)
		(legacy_teardrops no)
	)
	(paper "A4")
	(title_block
		(title "Wiwynn_Tioga_Pass_MB.brd")
		(comment 1 "Tioga Pass / footprints 41-43 of 4770")
	)
	(layers
		(0 "F.Cu" signal "TOP")
		(4 "In1.Cu" signal "L2GND")
		(6 "In2.Cu" signal "L3")
		(8 "In3.Cu" signal "L4GND")
		(10 "In4.Cu" signal "L5")
		(12 "In5.Cu" signal "L6GND")
		(14 "In6.Cu" signal "L7VCC")
		(16 "In7.Cu" signal "L8VCC")
		(18 "In8.Cu" signal "L9GND")
		(20 "In9.Cu" signal "L10")
		(22 "In10.Cu" signal "L11GND")
		(24 "In11.Cu" signal "L12")
		(26 "In12.Cu" signal "L13GND")
		(2 "B.Cu" signal "BOTTOM")
		(9 "F.Adhes" user "F.Adhesive")
		(11 "B.Adhes" user "B.Adhesive")
		(13 "F.Paste" user "Package Geometry/Pastemask Top")
		(15 "B.Paste" user "Package Geometry/Pastemask Bottom")
		(5 "F.SilkS" user "Ref Des/Silkscreen Top")
		(7 "B.SilkS" user "Ref Des/Silkscreen Bottom")
		(1 "F.Mask" user "Board Geometry/Soldermask Top")
		(3 "B.Mask" user "Board Geometry/Soldermask Bottom")
		(17 "Dwgs.User" user "User.Drawings")
		(19 "Cmts.User" user "User.Comments")
		(21 "Eco1.User" user "User.Eco1")
		(23 "Eco2.User" user "User.Eco2")
		(25 "Edge.Cuts" user "Board Geometry/Outline")
		(27 "Margin" user)
		(31 "F.CrtYd" user "Package Geometry/Place Bound Top")
		(29 "B.CrtYd" user "Package Geometry/Place Bound Bottom")
		(35 "F.Fab" user "Ref Des/Assembly Top")
		(33 "B.Fab" user "Ref Des/Assembly Bottom")
	)
	(footprint ""
		(layer "F.Cu")
		(at 5.20446 -132.49402 180)
		(property "Reference" "C1B3"
			(at -0.8382 -0.67818 180)
			(unlocked yes)
			(layer "F.SilkS")
			(effects
				(font
					(size 0.4064 0.254)
					(thickness 0.1524)
				)
				(justify left)
			)
		)
		(property "Value" ""
			(at 0 0 180)
			(layer "F.Fab")
			(effects
				(font
					(size 1.27 1.27)
				)
			)
		)
		(duplicate_pad_numbers_are_jumpers no)
		(fp_poly
			(pts
				(xy 0.3048 -0.1016) (xy 0.3048 0.9906) (xy -0.3048 0.9906) (xy -0.3048 -0.1016)
			)
			(stroke
				(width 0)
				(type default)
			)
			(fill no)
			(layer "F.CrtYd")
		)
		(fp_line
			(start 0.3048 0.9906)
			(end 0.3048 -0.1016)
			(stroke
				(width 0.1)
				(type default)
			)
			(layer "F.Fab")
		)
		(fp_line
			(start 0.3048 -0.1016)
			(end -0.3048 -0.1016)
			(stroke
				(width 0.1)
				(type default)
			)
			(layer "F.Fab")
		)
		(fp_line
			(start -0.3048 0.9906)
			(end 0.3048 0.9906)
			(stroke
				(width 0.1)
				(type default)
			)
			(layer "F.Fab")
		)
		(fp_line
			(start -0.3048 -0.1016)
			(end -0.3048 0.9906)
			(stroke
				(width 0.1)
				(type default)
			)
			(layer "F.Fab")
		)
		(pad "1" smd rect
			(at 0 0 180)
			(size 0.508 0.508)
			(layers "F.Cu" "F.Mask" "F.Paste")
			(net "VR_PVDDQ_KLM_VD12")
		)
		(pad "2" smd rect
			(at 0 0.889 180)
			(size 0.508 0.508)
			(layers "F.Cu" "F.Mask" "F.Paste")
			(net "GND")
		)
		(zone
			(layer "F.Cu")
			(hatch none 0.5)
			(connect_pads
				(clearance 0)
			)
			(min_thickness 0.25)
			(keepout
				(tracks not_allowed)
				(vias allowed)
				(pads allowed)
				(copperpour not_allowed)
				(footprints allowed)
			)
			(placement
				(enabled no)
				(sheetname "")
			)
			(fill
				(thermal_gap 0.5)
				(thermal_bridge_width 0.5)
				(island_removal_mode 0)
			)
			(polygon
				(pts
					(xy 5.45846 -133.12902) (xy 4.95046 -133.12902) (xy 4.95046 -132.74802) (xy 5.45846 -132.74802)
				)
			)
		)
		(zone
			(layer "F.Cu")
			(hatch none 0.5)
			(connect_pads
				(clearance 0)
			)
			(min_thickness 0.25)
			(keepout
				(tracks allowed)
				(vias not_allowed)
				(pads allowed)
				(copperpour not_allowed)
				(footprints allowed)
			)
			(placement
				(enabled no)
				(sheetname "")
			)
			(fill
				(thermal_gap 0.5)
				(thermal_bridge_width 0.5)
				(island_removal_mode 0)
			)
			(polygon
				(pts
					(xy 5.45846 -132.74802) (xy 4.95046 -132.74802) (xy 4.95046 -133.12902) (xy 5.45846 -133.12902)
				)
			)
		)
	)
	(footprint ""
		(layer "F.Cu")
		(at 273.369024 -77.429614)
		(property "Reference" "C5D36"
			(at 0 0 0)
			(layer "F.SilkS")
			(hide yes)
			(effects
				(font
					(size 1.27 1.27)
				)
			)
		)
		(property "Value" ""
			(at 0 0 0)
			(layer "F.Fab")
			(effects
				(font
					(size 1.27 1.27)
				)
			)
		)
		(duplicate_pad_numbers_are_jumpers no)
		(fp_poly
			(pts
				(xy -0.4953 -0.2032) (xy 0.4953 -0.2032) (xy 0.4953 1.6002) (xy -0.4953 1.6002)
			)
			(stroke
				(width 0)
				(type default)
			)
			(fill no)
			(layer "F.CrtYd")
		)
		(fp_line
			(start -0.4953 -0.2032)
			(end 0.4953 -0.2032)
			(stroke
				(width 0.1)
				(type default)
			)
			(layer "F.Fab")
		)
		(fp_line
			(start -0.4953 1.6002)
			(end -0.4953 -0.2032)
			(stroke
				(width 0.1)
				(type default)
			)
			(layer "F.Fab")
		)
		(fp_line
			(start 0.4953 -0.2032)
			(end 0.4953 1.6002)
			(stroke
				(width 0.1)
				(type default)
			)
			(layer "F.Fab")
		)
		(fp_line
			(start 0.4953 1.6002)
			(end -0.4953 1.6002)
			(stroke
				(width 0.1)
				(type default)
			)
			(layer "F.Fab")
		)
		(pad "1" smd rect
			(at 0 0)
			(size 0.762 0.889)
			(layers "F.Cu" "F.Mask" "F.Paste")
			(net "PVCCMCP_CPU0")
		)
		(pad "2" smd rect
			(at 0 1.397)
			(size 0.762 0.889)
			(layers "F.Cu" "F.Mask" "F.Paste")
			(net "GND")
		)
		(zone
			(layer "F.Cu")
			(hatch none 0.5)
			(connect_pads
				(clearance 0)
			)
			(min_thickness 0.25)
			(keepout
				(tracks not_allowed)
				(vias allowed)
				(pads allowed)
				(copperpour not_allowed)
				(footprints allowed)
			)
			(placement
				(enabled no)
				(sheetname "")
			)
			(fill
				(thermal_gap 0.5)
				(thermal_bridge_width 0.5)
				(island_removal_mode 0)
			)
			(polygon
				(pts
					(xy 272.988024 -76.985114) (xy 273.750024 -76.985114) (xy 273.750024 -76.477114) (xy 272.988024 -76.477114)
				)
			)
		)
	)
	(footprint ""
		(layer "F.Cu")
		(at 179.197 -58.166 90)
		(property "Reference" "C4E22"
			(at 0 0 90)
			(layer "F.SilkS")
			(hide yes)
			(effects
				(font
					(size 1.27 1.27)
				)
			)
		)
		(property "Value" ""
			(at 0 0 90)
			(layer "F.Fab")
			(effects
				(font
					(size 1.27 1.27)
				)
			)
		)
		(duplicate_pad_numbers_are_jumpers no)
		(fp_poly
			(pts
				(xy 0.3048 -0.1016) (xy 0.3048 0.9906) (xy -0.3048 0.9906) (xy -0.3048 -0.1016)
			)
			(stroke
				(width 0)
				(type default)
			)
			(fill no)
			(layer "F.CrtYd")
		)
		(fp_line
			(start 0.3048 -0.1016)
			(end -0.3048 -0.1016)
			(stroke
				(width 0.1)
				(type default)
			)
			(layer "F.Fab")
		)
		(fp_line
			(start -0.3048 -0.1016)
			(end -0.3048 0.9906)
			(stroke
				(width 0.1)
				(type default)
			)
			(layer "F.Fab")
		)
		(fp_line
			(start 0.3048 0.9906)
			(end 0.3048 -0.1016)
			(stroke
				(width 0.1)
				(type default)
			)
			(layer "F.Fab")
		)
		(fp_line
			(start -0.3048 0.9906)
			(end 0.3048 0.9906)
			(stroke
				(width 0.1)
				(type default)
			)
			(layer "F.Fab")
		)
		(pad "1" smd rect
			(at 0 0 90)
			(size 0.508 0.508)
			(layers "F.Cu" "F.Mask" "F.Paste")
			(net "VR_PVCCIO_CPU1_PH1_VCIN")
		)
		(pad "2" smd rect
			(at 0 0.889 90)
			(size 0.508 0.508)
			(layers "F.Cu" "F.Mask" "F.Paste")
			(net "GND")
		)
		(zone
			(layer "F.Cu")
			(hatch none 0.5)
			(connect_pads
				(clearance 0)
			)
			(min_thickness 0.25)
			(keepout
				(tracks allowed)
				(vias not_allowed)
				(pads allowed)
				(copperpour not_allowed)
				(footprints allowed)
			)
			(placement
				(enabled no)
				(sheetname "")
			)
			(fill
				(thermal_gap 0.5)
				(thermal_bridge_width 0.5)
				(island_removal_mode 0)
			)
			(polygon
				(pts
					(xy 179.451 -57.912) (xy 179.451 -58.42) (xy 179.832 -58.42) (xy 179.832 -57.912)
				)
			)
		)
		(zone
			(layer "F.Cu")
			(hatch none 0.5)
			(connect_pads
				(clearance 0)
			)
			(min_thickness 0.25)
			(keepout
				(tracks not_allowed)
				(vias allowed)
				(pads allowed)
				(copperpour not_allowed)
				(footprints allowed)
			)
			(placement
				(enabled no)
				(sheetname "")
			)
			(fill
				(thermal_gap 0.5)
				(thermal_bridge_width 0.5)
				(island_removal_mode 0)
			)
			(polygon
				(pts
					(xy 179.832 -57.912) (xy 179.832 -58.42) (xy 179.451 -58.42) (xy 179.451 -57.912)
				)
			)
		)
	)
)
